FILE_TYPE = CONNECTIVITY;
{Allegro Design Entry HDL 17.2-2016 S081 (4005846) 1/11/2022}
"PAGE_NUMBER" = 104;
0"NC";
1"M_H_CPU1_SA_CB<7:0>";
2"M_H_CPU1_SA_CA<6:0>";
3"M_H_CPU1_SB_CA<6:0>";
4"M_H_CPU1_SB_CB<7:0>";
5"M_H_CPU1_SA_DQ<31:0>";
6"M_H_CPU1_SB_DQ<31:0>";
7"M_H_CPU1_SA_DQS_DN<9:0>";
8"M_H_CPU1_SA_DQS_DP<9:0>";
9"M_H_CPU1_SB_DQS_DN<9:0>";
10"M_H_CPU1_SB_DQS_DP<9:0>";
11"GND\g";
12"GND\g";
13"P3V3_STBY\g";
14"I3C_SPD_DDRGL_CPU1_SCL";
15"I3C_SPD_DDRH_CPU1_SCL";
16"PWRGD_CHH_CPU1_DIMM";
17"I3C_SPD_DDRGL_CPU1_SDA";
18"TP_CHH_CPU1_DIMM_RFU_3";
19"TP_CHH_CPU1_DIMM_RFU_4";
20"TP_CHH_CPU1_DIMM_RFU_5";
21"PD_CHH_CPU1_DIMM_SAA";
22"P3V3_STBY\g";
23"M_H_CPU1_RESET_N";
24"M_H_CPU1_ALERT_N";
25"P12V_MEM_1\g";
26"GND\g";
27"GND\g";
28"M_H_CPU1_SA_DQ<15>";
29"M_H_CPU1_SA_DQ<16>";
30"M_H_CPU1_SA_DQS_DN<9>";
31"M_H_CPU1_SB_DQS_DP<9>";
32"M_H_CPU1_SB_DQS_DN<9>";
33"M_H_CPU1_SA_DQS_DP<9>";
34"M_H_CPU1_SA_DQS_DP<8>";
35"M_H_CPU1_SA_DQS_DN<8>";
36"M_H_CPU1_SB_DQS_DN<7>";
37"M_H_CPU1_SA_DQS_DP<7>";
38"M_H_CPU1_SB_DQS_DP<6>";
39"M_H_CPU1_SB_DQS_DN<6>";
40"M_H_CPU1_SA_DQS_DN<6>";
41"M_H_CPU1_SB_DQS_DP<5>";
42"M_H_CPU1_SB_DQS_DN<5>";
43"M_H_CPU1_SA_DQS_DP<5>";
44"M_H_CPU1_SA_DQS_DN<5>";
45"M_H_CPU1_SB_DQS_DP<4>";
46"M_H_CPU1_SB_DQS_DN<4>";
47"M_H_CPU1_SA_DQS_DP<4>";
48"M_H_CPU1_SA_DQS_DN<4>";
49"M_H_CPU1_SB_DQS_DP<3>";
50"M_H_CPU1_SB_DQS_DN<3>";
51"M_H_CPU1_SA_DQS_DP<3>";
52"M_H_CPU1_SA_DQS_DN<3>";
53"M_H_CPU1_SB_DQS_DP<2>";
54"M_H_CPU1_SB_DQS_DN<2>";
55"M_H_CPU1_SA_DQS_DP<2>";
56"M_H_CPU1_SA_DQS_DN<2>";
57"M_H_CPU1_SB_DQS_DP<1>";
58"M_H_CPU1_SB_DQS_DN<1>";
59"M_H_CPU1_SA_DQS_DP<1>";
60"M_H_CPU1_SA_DQS_DN<1>";
61"M_H_CPU1_SB_DQS_DP<0>";
62"M_H_CPU1_SB_DQS_DN<0>";
63"M_H_CPU1_SA_DQS_DP<0>";
64"M_H_CPU1_SA_DQS_DN<0>";
65"M_H_CPU1_SB_DQS_DP<7>";
66"M_H_CPU1_SB_DQS_DN<8>";
67"M_H_CPU1_SB_DQS_DP<8>";
68"M_H_CPU1_SA_DQS_DP<6>";
69"M_H_CPU1_SA_DQS_DN<7>";
70"M_H_CPU1_SA_CA<5>";
71"M_H_CPU1_SA_CA<4>";
72"M_H_CPU1_SA_DQ<29>";
73"M_H_CPU1_SA_DQ<30>";
74"M_H_CPU1_SA_DQ<28>";
75"TP_CHH_CPU1_DIMM_RFU_0";
76"TP_CHH_CPU1_DIMM_RFU_1";
77"TP_CHH_CPU1_DIMM_RFU_2";
78"TP_CHH_CPU1_DIMM_RFU_6";
79"M_H_CPU1_SB_PAR";
80"M_H_CPU1_SA_PAR";
81"M_H_CPU1_SB_RSP<0>";
82"M_H_CPU1_SA_RSP<0>";
83"M_H_CPU1_SB_DQ<0>";
84"M_H_CPU1_SB_DQ<1>";
85"M_H_CPU1_SB_DQ<2>";
86"M_H_CPU1_SB_DQ<3>";
87"M_H_CPU1_SB_DQ<4>";
88"M_H_CPU1_SB_DQ<5>";
89"M_H_CPU1_SB_DQ<6>";
90"M_H_CPU1_SB_DQ<7>";
91"M_H_CPU1_SB_DQ<8>";
92"M_H_CPU1_SB_DQ<9>";
93"M_H_CPU1_SB_DQ<10>";
94"M_H_CPU1_SB_DQ<11>";
95"M_H_CPU1_SB_DQ<12>";
96"M_H_CPU1_SB_DQ<13>";
97"M_H_CPU1_SB_DQ<14>";
98"M_H_CPU1_SB_DQ<15>";
99"M_H_CPU1_SB_DQ<16>";
100"M_H_CPU1_SB_DQ<17>";
101"M_H_CPU1_SB_DQ<18>";
102"M_H_CPU1_SB_DQ<19>";
103"M_H_CPU1_SB_DQ<20>";
104"M_H_CPU1_SB_DQ<21>";
105"M_H_CPU1_SB_DQ<22>";
106"M_H_CPU1_SB_DQ<23>";
107"M_H_CPU1_SB_DQ<24>";
108"M_H_CPU1_SB_DQ<25>";
109"M_H_CPU1_SB_DQ<26>";
110"M_H_CPU1_SB_DQ<27>";
111"M_H_CPU1_SB_DQ<28>";
112"M_H_CPU1_SB_DQ<29>";
113"M_H_CPU1_SB_DQ<30>";
114"M_H_CPU1_SB_DQ<31>";
115"M_H_CPU1_SA_DQ<0>";
116"M_H_CPU1_SA_DQ<1>";
117"M_H_CPU1_SA_DQ<2>";
118"M_H_CPU1_SA_DQ<3>";
119"M_H_CPU1_SA_DQ<4>";
120"M_H_CPU1_SA_DQ<5>";
121"M_H_CPU1_SA_DQ<6>";
122"M_H_CPU1_SA_DQ<7>";
123"M_H_CPU1_SA_DQ<8>";
124"M_H_CPU1_SA_DQ<9>";
125"M_H_CPU1_SA_DQ<10>";
126"M_H_CPU1_SA_DQ<11>";
127"M_H_CPU1_SA_DQ<12>";
128"M_H_CPU1_SA_DQ<13>";
129"M_H_CPU1_SA_DQ<14>";
130"M_H_CPU1_SA_DQ<17>";
131"M_H_CPU1_SA_DQ<18>";
132"M_H_CPU1_SA_DQ<19>";
133"M_H_CPU1_SA_DQ<20>";
134"M_H_CPU1_SA_DQ<21>";
135"M_H_CPU1_SA_DQ<22>";
136"M_H_CPU1_SA_DQ<23>";
137"M_H_CPU1_SA_DQ<24>";
138"M_H_CPU1_SA_DQ<25>";
139"M_H_CPU1_SA_DQ<26>";
140"M_H_CPU1_SA_DQ<27>";
141"M_H_CPU1_SB_CS_N<1>";
142"M_H_CPU1_SA_CS_N<1>";
143"M_H_CPU1_SB_CS_N<0>";
144"M_H_CPU1_SA_CS_N<0>";
145"M_H_CPU1_CLK_DP<0>";
146"M_H_CPU1_CLK_DN<0>";
147"M_H_CPU1_SB_CB<0>";
148"M_H_CPU1_SB_CB<1>";
149"M_H_CPU1_SB_CB<2>";
150"M_H_CPU1_SB_CB<3>";
151"M_H_CPU1_SB_CB<4>";
152"M_H_CPU1_SB_CB<5>";
153"M_H_CPU1_SB_CB<6>";
154"M_H_CPU1_SA_CB<0>";
155"M_H_CPU1_SA_CB<2>";
156"M_H_CPU1_SA_CB<3>";
157"M_H_CPU1_SA_CB<5>";
158"M_H_CPU1_SA_CB<6>";
159"M_H_CPU1_SB_CA<6>";
160"M_H_CPU1_SA_CA<6>";
161"M_H_CPU1_SB_CA<5>";
162"M_H_CPU1_SB_CA<4>";
163"M_H_CPU1_SB_CA<3>";
164"M_H_CPU1_SA_CA<3>";
165"M_H_CPU1_SB_CA<2>";
166"M_H_CPU1_SA_CA<2>";
167"M_H_CPU1_SB_CA<1>";
168"M_H_CPU1_SA_CA<1>";
169"M_H_CPU1_SB_CA<0>";
170"M_H_CPU1_SA_CA<0>";
171"M_H_CPU1_SB_CB<7>";
172"M_H_CPU1_SA_CB<1>";
173"M_H_CPU1_SA_CB<4>";
174"M_H_CPU1_SA_CB<7>";
175"M_H_CPU1_SA_DQ<31>";
176"GND\g";
177"PWRGD_CHGL_CPU1";
178"PD_CHH_CPU1_DIMM_SAA";
%"TAP"
"1","(-5950,4200)","0","mstr_standard","I100";
;
CDS_LIB"mstr_standard"
BODY_TYPE"PLUMBING"
HDL_TAP"TRUE";
"B \NAC \NWC"5;
"S \NAC"
BN"7"122;
%"TAP"
"1","(-5950,4250)","0","mstr_standard","I101";
;
CDS_LIB"mstr_standard"
BODY_TYPE"PLUMBING"
HDL_TAP"TRUE";
"B \NAC \NWC"5;
"S \NAC"
BN"8"123;
%"TAP"
"1","(-5950,4300)","0","mstr_standard","I102";
;
CDS_LIB"mstr_standard"
BODY_TYPE"PLUMBING"
HDL_TAP"TRUE";
"B \NAC \NWC"5;
"S \NAC"
BN"9"124;
%"TAP"
"1","(-5950,4400)","0","mstr_standard","I103";
;
CDS_LIB"mstr_standard"
BODY_TYPE"PLUMBING"
HDL_TAP"TRUE";
"B \NAC \NWC"5;
"S \NAC"
BN"11"126;
%"TAP"
"1","(-5950,4350)","0","mstr_standard","I104";
;
CDS_LIB"mstr_standard"
BODY_TYPE"PLUMBING"
HDL_TAP"TRUE";
"B \NAC \NWC"5;
"S \NAC"
BN"10"125;
%"TAP"
"1","(-5950,4450)","0","mstr_standard","I105";
;
CDS_LIB"mstr_standard"
BODY_TYPE"PLUMBING"
HDL_TAP"TRUE";
"B \NAC \NWC"5;
"S \NAC"
BN"12"127;
%"TAP"
"1","(-5950,4500)","0","mstr_standard","I106";
;
CDS_LIB"mstr_standard"
BODY_TYPE"PLUMBING"
HDL_TAP"TRUE";
"B \NAC \NWC"5;
"S \NAC"
BN"13"128;
%"TAP"
"1","(-5950,4550)","0","mstr_standard","I107";
;
CDS_LIB"mstr_standard"
BODY_TYPE"PLUMBING"
HDL_TAP"TRUE";
"B \NAC \NWC"5;
"S \NAC"
BN"14"129;
%"TAP"
"1","(-5950,4650)","0","mstr_standard","I108";
;
CDS_LIB"mstr_standard"
BODY_TYPE"PLUMBING"
HDL_TAP"TRUE";
"B \NAC \NWC"5;
"S \NAC"
BN"16"29;
%"TAP"
"1","(-5950,4600)","0","mstr_standard","I109";
;
CDS_LIB"mstr_standard"
BODY_TYPE"PLUMBING"
HDL_TAP"TRUE";
"B \NAC \NWC"5;
"S \NAC"
BN"15"28;
%"TAP"
"1","(-5950,4750)","0","mstr_standard","I110";
;
CDS_LIB"mstr_standard"
BODY_TYPE"PLUMBING"
HDL_TAP"TRUE";
"B \NAC \NWC"5;
"S \NAC"
BN"18"131;
%"TAP"
"1","(-5950,4700)","0","mstr_standard","I111";
;
CDS_LIB"mstr_standard"
BODY_TYPE"PLUMBING"
HDL_TAP"TRUE";
"B \NAC \NWC"5;
"S \NAC"
BN"17"130;
%"TAP"
"1","(-5950,4800)","0","mstr_standard","I112";
;
CDS_LIB"mstr_standard"
BODY_TYPE"PLUMBING"
HDL_TAP"TRUE";
"B \NAC \NWC"5;
"S \NAC"
BN"19"132;
%"TAP"
"1","(-5950,4900)","0","mstr_standard","I113";
;
CDS_LIB"mstr_standard"
BODY_TYPE"PLUMBING"
HDL_TAP"TRUE";
"B \NAC \NWC"5;
"S \NAC"
BN"21"134;
%"TAP"
"1","(-5950,4850)","0","mstr_standard","I114";
;
CDS_LIB"mstr_standard"
BODY_TYPE"PLUMBING"
HDL_TAP"TRUE";
"B \NAC \NWC"5;
"S \NAC"
BN"20"133;
%"TAP"
"1","(-5950,4950)","0","mstr_standard","I115";
;
CDS_LIB"mstr_standard"
BODY_TYPE"PLUMBING"
HDL_TAP"TRUE";
"B \NAC \NWC"5;
"S \NAC"
BN"22"135;
%"TAP"
"1","(-5950,5000)","0","mstr_standard","I116";
;
CDS_LIB"mstr_standard"
BODY_TYPE"PLUMBING"
HDL_TAP"TRUE";
"B \NAC \NWC"5;
"S \NAC"
BN"23"136;
%"TAP"
"1","(-5950,5100)","0","mstr_standard","I117";
;
CDS_LIB"mstr_standard"
BODY_TYPE"PLUMBING"
HDL_TAP"TRUE";
"B \NAC \NWC"5;
"S \NAC"
BN"25"138;
%"TAP"
"1","(-5950,5050)","0","mstr_standard","I118";
;
CDS_LIB"mstr_standard"
BODY_TYPE"PLUMBING"
HDL_TAP"TRUE";
"B \NAC \NWC"5;
"S \NAC"
BN"24"137;
%"TAP"
"1","(-5950,5150)","0","mstr_standard","I119";
;
CDS_LIB"mstr_standard"
BODY_TYPE"PLUMBING"
HDL_TAP"TRUE";
"B \NAC \NWC"5;
"S \NAC"
BN"26"139;
%"TAP"
"1","(-5950,5300)","0","mstr_standard","I120";
;
CDS_LIB"mstr_standard"
BODY_TYPE"PLUMBING"
HDL_TAP"TRUE";
"B \NAC \NWC"5;
"S \NAC"
BN"29"72;
%"TAP"
"1","(-5950,5250)","0","mstr_standard","I121";
;
CDS_LIB"mstr_standard"
BODY_TYPE"PLUMBING"
HDL_TAP"TRUE";
"B \NAC \NWC"5;
"S \NAC"
BN"28"74;
%"TAP"
"1","(-5950,5200)","0","mstr_standard","I122";
;
CDS_LIB"mstr_standard"
BODY_TYPE"PLUMBING"
HDL_TAP"TRUE";
"B \NAC \NWC"5;
"S \NAC"
BN"27"140;
%"TAP"
"1","(-5950,5350)","0","mstr_standard","I123";
;
CDS_LIB"mstr_standard"
BODY_TYPE"PLUMBING"
HDL_TAP"TRUE";
"B \NAC \NWC"5;
"S \NAC"
BN"30"73;
%"TAP"
"1","(-5950,5400)","0","mstr_standard","I124";
;
CDS_LIB"mstr_standard"
BODY_TYPE"PLUMBING"
HDL_TAP"TRUE";
"B \NAC \NWC"5;
"S \NAC"
BN"31"175;
%"GND"
"1","(-6375,850)","0","mstr_symbols","I127";
;
SIZE"1B"
CDS_LIB"mstr_symbols"
BOM_COST"MEM"
BODY_TYPE"PLUMBING"
VOLTAGE"0.0"
HDL_POWER"GND";
"A\NAC"11;
%"Q_RES"
"2","(-6375,1075)","0","pure_quanta","I128";
;
LOCATION"R774"
$SEC"1"
CDS_SEC"1"
WATTAGE"1/16W"
MATERIAL"CHIP"
TOLERANCE"1%"
VALUE"15.4K"
PART_NUMBER"CS31542FB02"
PACK_TYPE"0402LF"
CDS_LIB"pure_quanta";
"A"
$PN"1"178;
"B"
$PN"2"11;
%"GND"
"1","(-2125,1875)","0","mstr_symbols","I140";
;
SIZE"1B"
CDS_LIB"mstr_symbols"
BODY_TYPE"PLUMBING"
VOLTAGE"0.0"
HDL_POWER"GND";
"A\NAC"27;
%"GND"
"1","(-325,1650)","0","mstr_symbols","I141";
;
SIZE"1B"
CDS_LIB"mstr_symbols"
BODY_TYPE"PLUMBING"
VOLTAGE"0.0"
HDL_POWER"GND";
"A\NAC"26;
%"SCONN288_DDR506112002KQ"
"3","(-1225,3650)","0","pure_quanta","I174";
;
LOCATION"J27"
$SEC"3"
CDS_SEC"3"
PART_TYPE"SMLF"
MATERIAL"IO"
VALUE"SCONN288_DDR506112002KQ"
PART_NUMBER"DFHST8FS479"
CDS_LMAN_SYM_OUTLINE"-450,1800,450,-1750"
NEEDS_NO_SIZE"TRUE"
CDS_LIB"pure_quanta";
"G3"
$PN"G3"26;
"G2"
$PN"G2"26;
"G1"
$PN"G1"26;
"VSS62"
$PN"141"26;
"VSS61"
$PN"139"26;
"VSS60"
$PN"136"26;
"VSS58"
$PN"132"26;
"VSS104"
$PN"240"27;
"VSS102"
$PN"235"27;
"VSS100"
$PN"230"27;
"VIN_BULK2"
$PN"146"25;
"VIN_BULK1"
$PN"145"25;
"VIN_BULK0"
$PN"1"25;
"VSS126"
$PN"288"27;
"VSS125"
$PN"286"27;
"VSS124"
$PN"284"27;
"VSS123"
$PN"281"27;
"VSS122"
$PN"279"27;
"VSS121"
$PN"277"27;
"VSS120"
$PN"275"27;
"VSS119"
$PN"273"27;
"VSS118"
$PN"270"27;
"VSS117"
$PN"268"27;
"VSS116"
$PN"266"27;
"VSS115"
$PN"264"27;
"VSS114"
$PN"262"27;
"VSS113"
$PN"259"27;
"VSS112"
$PN"257"27;
"VSS111"
$PN"255"27;
"VSS110"
$PN"253"27;
"VSS109"
$PN"251"27;
"VSS108"
$PN"248"27;
"VSS107"
$PN"246"27;
"VSS106"
$PN"244"27;
"VSS105"
$PN"242"27;
"VSS103"
$PN"237"27;
"VSS101"
$PN"233"27;
"VSS99"
$PN"228"27;
"VSS98"
$PN"226"27;
"VSS97"
$PN"224"27;
"VSS96"
$PN"222"27;
"VSS95"
$PN"219"27;
"VSS94"
$PN"216"27;
"VSS93"
$PN"214"27;
"VSS92"
$PN"212"27;
"VSS91"
$PN"210"27;
"VSS90"
$PN"208"27;
"VSS89"
$PN"206"27;
"VSS88"
$PN"204"27;
"VSS87"
$PN"202"27;
"VSS86"
$PN"199"27;
"VSS85"
$PN"197"27;
"VSS84"
$PN"195"27;
"VSS83"
$PN"193"27;
"VSS82"
$PN"191"27;
"VSS81"
$PN"188"27;
"VSS80"
$PN"186"27;
"VSS79"
$PN"184"27;
"VSS78"
$PN"182"27;
"VSS77"
$PN"180"27;
"VSS76"
$PN"177"27;
"VSS75"
$PN"175"27;
"VSS74"
$PN"173"27;
"VSS73"
$PN"171"27;
"VSS72"
$PN"169"27;
"VSS71"
$PN"166"27;
"VSS70"
$PN"164"27;
"VSS69"
$PN"162"27;
"VSS68"
$PN"160"27;
"VSS67"
$PN"158"27;
"VSS66"
$PN"155"27;
"VSS65"
$PN"153"27;
"VSS64"
$PN"151"27;
"VSS63"
$PN"143"26;
"VSS59"
$PN"134"26;
"VSS57"
$PN"130"26;
"VSS56"
$PN"128"26;
"VSS55"
$PN"125"26;
"VSS54"
$PN"123"26;
"VSS53"
$PN"121"26;
"VSS52"
$PN"119"26;
"VSS51"
$PN"117"26;
"VSS50"
$PN"114"26;
"VSS49"
$PN"112"26;
"VSS48"
$PN"110"26;
"VSS47"
$PN"108"26;
"VSS46"
$PN"106"26;
"VSS45"
$PN"103"26;
"VSS44"
$PN"101"26;
"VSS43"
$PN"99"26;
"VSS42"
$PN"97"26;
"VSS41"
$PN"95"26;
"VSS40"
$PN"92"26;
"VSS39"
$PN"90"26;
"VSS38"
$PN"88"26;
"VSS37"
$PN"85"26;
"VSS36"
$PN"83"26;
"VSS35"
$PN"81"26;
"VSS34"
$PN"79"26;
"VSS33"
$PN"77"26;
"VSS32"
$PN"75"26;
"VSS31"
$PN"73"26;
"VSS30"
$PN"71"26;
"VSS29"
$PN"69"26;
"VSS28"
$PN"67"26;
"VSS27"
$PN"65"26;
"VSS26"
$PN"63"26;
"VSS25"
$PN"61"26;
"VSS24"
$PN"59"26;
"VSS23"
$PN"57"26;
"VSS22"
$PN"54"26;
"VSS21"
$PN"52"26;
"VSS20"
$PN"50"26;
"VSS19"
$PN"48"26;
"VSS18"
$PN"46"26;
"VSS17"
$PN"43"26;
"VSS16"
$PN"41"26;
"VSS15"
$PN"39"26;
"VSS14"
$PN"37"26;
"VSS13"
$PN"35"26;
"VSS12"
$PN"32"26;
"VSS11"
$PN"30"26;
"VSS10"
$PN"28"26;
"VSS9"
$PN"26"26;
"VSS8"
$PN"24"26;
"VSS7"
$PN"21"26;
"VSS6"
$PN"19"26;
"VSS5"
$PN"17"26;
"VSS4"
$PN"15"26;
"VSS3"
$PN"13"26;
"VSS2"
$PN"10"26;
"VSS1"
$PN"8"26;
"VSS0"
$PN"6"26;
%"Q_CAP"
"1","(-8575,3225)","2","pure_quanta","I185";
;
LOCATION"C164"
$SEC"1"
CDS_SEC"1"
MATERIAL"X7R"
TOLERANCE"10%"
VALUE"0.1UF"
PART_NUMBER"CH4104K1B00"
VOLTAGE"25V"
PACK_TYPE"0402"
BOM_COST"MEM"
CDS_LIB"pure_quanta"
ROOM"MEM_CH_A_CPU0_DIMM1";
"B"
$PN"2"12;
"A"
$PN"1"22;
%"GND"
"1","(-8575,3000)","0","mstr_symbols","I186";
;
BOM_COST"MEM"
SIZE"1B"
CDS_LIB"mstr_symbols"
BODY_TYPE"PLUMBING"
VOLTAGE"0"
ROOM"MEM_EFGH_DECOUPLING_CAPS"
HDL_POWER"GND";
"A\NAC"12;
%"Q_RES"
"1","(-8475,2150)","2","pure_quanta","I189";
;
LOCATION"R310"
$SEC"1"
CDS_SEC"1"
VALUE"0"
BOM_COST"MEM"
CDS_LIB"pure_quanta"
WATTAGE"1/16W"
MATERIAL"CHIP"
TOLERANCE"5%"
PART_NUMBER"CS00002JB38"
PACK_TYPE"0402LF"
ROOM"RST_CPU0_PLD_TO_DIMM";
"B"
$PN"2"177;
"A"
$PN"1"16;
%"Q_RES"
"2","(-8350,2300)","0","pure_quanta","I190";
;
LOCATION"R111"
$SEC"1"
CDS_SEC"1"
WATTAGE"1/16W"
MATERIAL"EMPTY"
TOLERANCE"5%"
VALUE"1K"
PACK_TYPE"0402LF"
BOM_COST"MEM"
CDS_LIB"pure_quanta"
PART_NUMBER"TMP_QCS21002JB34"
ROOM"MEM_CH_A_CPU0_DIMM1";
"A"
$PN"1"13;
"B"
$PN"2"16;
%"VCC_CORE"
"1","(-8350,2475)","0","mstr_symbols","I192";
;
HDL_POWER"P3V3_STBY"
CDS_LIB"mstr_symbols"
VOLTAGE"3.3"
ROOM"PVCCINFAON_CPU0_CTRL";
"A"13;
%"TAP"
"1","(-3225,3675)","0","mstr_standard","I193";
;
CDS_LIB"mstr_standard"
BODY_TYPE"PLUMBING"
HDL_TAP"TRUE";
"B \NAC \NWC"7;
"S \NAC"
BN"2"56;
%"TAP"
"1","(-3225,3775)","0","mstr_standard","I194";
;
CDS_LIB"mstr_standard"
BODY_TYPE"PLUMBING"
HDL_TAP"TRUE";
"B \NAC \NWC"7;
"S \NAC"
BN"3"52;
%"TAP"
"1","(-3425,3925)","0","mstr_standard","I195";
;
CDS_LIB"mstr_standard"
BODY_TYPE"PLUMBING"
HDL_TAP"TRUE";
"B \NAC \NWC"8;
"S \NAC"
BN"4"47;
%"TAP"
"1","(-3425,4025)","0","mstr_standard","I196";
;
CDS_LIB"mstr_standard"
BODY_TYPE"PLUMBING"
HDL_TAP"TRUE";
"B \NAC \NWC"8;
"S \NAC"
BN"5"43;
%"TAP"
"1","(-3225,4375)","0","mstr_standard","I202";
;
CDS_LIB"mstr_standard"
BODY_TYPE"PLUMBING"
HDL_TAP"TRUE";
"B \NAC \NWC"7;
"S \NAC"
BN"9"30;
%"TAP"
"1","(-3225,4275)","0","mstr_standard","I203";
;
CDS_LIB"mstr_standard"
BODY_TYPE"PLUMBING"
HDL_TAP"TRUE";
"B \NAC \NWC"7;
"S \NAC"
BN"8"35;
%"TAP"
"1","(-3425,4425)","0","mstr_standard","I204";
;
CDS_LIB"mstr_standard"
BODY_TYPE"PLUMBING"
HDL_TAP"TRUE";
"B \NAC \NWC"8;
"S \NAC"
BN"9"33;
%"TAP"
"1","(-3425,4325)","0","mstr_standard","I205";
;
CDS_LIB"mstr_standard"
BODY_TYPE"PLUMBING"
HDL_TAP"TRUE";
"B \NAC \NWC"8;
"S \NAC"
BN"8"34;
%"TAP"
"1","(-3225,4175)","0","mstr_standard","I206";
;
CDS_LIB"mstr_standard"
BODY_TYPE"PLUMBING"
HDL_TAP"TRUE";
"B \NAC \NWC"7;
"S \NAC"
BN"7"69;
%"TAP"
"1","(-3225,4075)","0","mstr_standard","I207";
;
CDS_LIB"mstr_standard"
BODY_TYPE"PLUMBING"
HDL_TAP"TRUE";
"B \NAC \NWC"7;
"S \NAC"
BN"6"40;
%"TAP"
"1","(-3225,3975)","0","mstr_standard","I208";
;
CDS_LIB"mstr_standard"
BODY_TYPE"PLUMBING"
HDL_TAP"TRUE";
"B \NAC \NWC"7;
"S \NAC"
BN"5"44;
%"TAP"
"1","(-3225,3875)","0","mstr_standard","I209";
;
CDS_LIB"mstr_standard"
BODY_TYPE"PLUMBING"
HDL_TAP"TRUE";
"B \NAC \NWC"7;
"S \NAC"
BN"4"48;
%"TAP"
"1","(-3225,3575)","0","mstr_standard","I210";
;
CDS_LIB"mstr_standard"
BODY_TYPE"PLUMBING"
HDL_TAP"TRUE";
"B \NAC \NWC"7;
"S \NAC"
BN"1"60;
%"TAP"
"1","(-3225,3475)","0","mstr_standard","I211";
;
CDS_LIB"mstr_standard"
BODY_TYPE"PLUMBING"
HDL_TAP"TRUE";
"B \NAC \NWC"7;
"S \NAC"
BN"0"64;
%"TAP"
"1","(-3225,3225)","0","mstr_standard","I212";
;
CDS_LIB"mstr_standard"
BODY_TYPE"PLUMBING"
HDL_TAP"TRUE";
"B \NAC \NWC"9;
"S \NAC"
BN"8"66;
%"TAP"
"1","(-3225,3325)","0","mstr_standard","I213";
;
CDS_LIB"mstr_standard"
BODY_TYPE"PLUMBING"
HDL_TAP"TRUE";
"B \NAC \NWC"9;
"S \NAC"
BN"9"32;
%"TAP"
"1","(-3425,4225)","0","mstr_standard","I214";
;
CDS_LIB"mstr_standard"
BODY_TYPE"PLUMBING"
HDL_TAP"TRUE";
"B \NAC \NWC"8;
"S \NAC"
BN"7"37;
%"TAP"
"1","(-3425,4125)","0","mstr_standard","I215";
;
CDS_LIB"mstr_standard"
BODY_TYPE"PLUMBING"
HDL_TAP"TRUE";
"B \NAC \NWC"8;
"S \NAC"
BN"6"68;
%"TAP"
"1","(-3425,3825)","0","mstr_standard","I216";
;
CDS_LIB"mstr_standard"
BODY_TYPE"PLUMBING"
HDL_TAP"TRUE";
"B \NAC \NWC"8;
"S \NAC"
BN"3"51;
%"TAP"
"1","(-3425,3725)","0","mstr_standard","I217";
;
CDS_LIB"mstr_standard"
BODY_TYPE"PLUMBING"
HDL_TAP"TRUE";
"B \NAC \NWC"8;
"S \NAC"
BN"2"55;
%"TAP"
"1","(-3425,3625)","0","mstr_standard","I218";
;
CDS_LIB"mstr_standard"
BODY_TYPE"PLUMBING"
HDL_TAP"TRUE";
"B \NAC \NWC"8;
"S \NAC"
BN"1"59;
%"TAP"
"1","(-3425,3525)","0","mstr_standard","I219";
;
CDS_LIB"mstr_standard"
BODY_TYPE"PLUMBING"
HDL_TAP"TRUE";
"B \NAC \NWC"8;
"S \NAC"
BN"0"63;
%"SCONN288_DDR506112002KQ"
"1","(-6800,3650)","0","pure_quanta","I22";
;
LOCATION"J27"
$SEC"1"
CDS_SEC"1"
VALUE"SCONN288_DDR506112002KQ"
PART_TYPE"SMLF"
PART_NUMBER"DFHST8FS479"
MATERIAL"IO"
CDS_LMAN_SYM_OUTLINE"-450,1900,450,-1850"
NEEDS_NO_SIZE"TRUE"
CDS_LIB"pure_quanta";
"PWR_GOOD||FAIL_N"
$PN"147"16;
"DQ31_A"
$PN"194"175;
"CB7_A"
$PN"205"174;
"CB4_A"
$PN"58"173;
"CB1_A"
$PN"53"172;
"CB7_B"
$PN"236"171;
"ALERT_N \B"
$PN"62"24;
"CA0_A"
$PN"66"170;
"CA0_B"
$PN"76"169;
"CA1_A"
$PN"211"168;
"CA1_B"
$PN"221"167;
"CA2_A"
$PN"68"166;
"CA2_B"
$PN"78"165;
"CA3_A"
$PN"213"164;
"CA3_B"
$PN"223"163;
"CA4_A"
$PN"70"71;
"CA4_B"
$PN"80"162;
"CA5_A"
$PN"215"70;
"CA5_B"
$PN"225"161;
"CA6_A"
$PN"72"160;
"CA6_B"
$PN"82"159;
"CB6_A"
$PN"203"158;
"CB5_A"
$PN"60"157;
"CB3_A"
$PN"198"156;
"CB2_A"
$PN"196"155;
"CB0_A"
$PN"51"154;
"CB6_B"
$PN"234"153;
"CB5_B"
$PN"91"152;
"CB4_B"
$PN"89"151;
"CB3_B"
$PN"243"150;
"CB2_B"
$PN"241"149;
"CB1_B"
$PN"98"148;
"CB0_B"
$PN"96"147;
"CK_C \B"
$PN"218"146;
"CK_T"
$PN"217"145;
"CS0_A_N"
$PN"64"144;
"CS0_B_N"
$PN"84"143;
"CS1_A_N"
$PN"209"142;
"CS1_B_N"
$PN"229"141;
"DQ30_A"
$PN"192"73;
"DQ29_A"
$PN"49"72;
"DQ28_A"
$PN"47"74;
"DQ27_A"
$PN"187"140;
"DQ26_A"
$PN"185"139;
"DQ25_A"
$PN"42"138;
"DQ24_A"
$PN"40"137;
"DQ23_A"
$PN"183"136;
"DQ22_A"
$PN"181"135;
"DQ21_A"
$PN"38"134;
"DQ20_A"
$PN"36"133;
"DQ19_A"
$PN"176"132;
"DQ18_A"
$PN"174"131;
"DQ17_A"
$PN"31"130;
"DQ16_A"
$PN"29"29;
"DQ15_A"
$PN"172"28;
"DQ14_A"
$PN"170"129;
"DQ13_A"
$PN"27"128;
"DQ12_A"
$PN"25"127;
"DQ11_A"
$PN"165"126;
"DQ10_A"
$PN"163"125;
"DQ9_A"
$PN"20"124;
"DQ8_A"
$PN"18"123;
"DQ7_A"
$PN"161"122;
"DQ6_A"
$PN"159"121;
"DQ5_A"
$PN"16"120;
"DQ4_A"
$PN"14"119;
"DQ3_A"
$PN"154"118;
"DQ2_A"
$PN"152"117;
"DQ1_A"
$PN"9"116;
"DQ0_A"
$PN"7"115;
"DQ31_B"
$PN"287"114;
"DQ30_B"
$PN"285"113;
"DQ29_B"
$PN"142"112;
"DQ28_B"
$PN"140"111;
"DQ27_B"
$PN"280"110;
"DQ26_B"
$PN"278"109;
"DQ25_B"
$PN"135"108;
"DQ24_B"
$PN"133"107;
"DQ23_B"
$PN"276"106;
"DQ22_B"
$PN"274"105;
"DQ21_B"
$PN"131"104;
"DQ20_B"
$PN"129"103;
"DQ19_B"
$PN"269"102;
"DQ18_B"
$PN"267"101;
"DQ17_B"
$PN"124"100;
"DQ16_B"
$PN"122"99;
"DQ15_B"
$PN"265"98;
"DQ14_B"
$PN"263"97;
"DQ13_B"
$PN"120"96;
"DQ12_B"
$PN"118"95;
"DQ11_B"
$PN"258"94;
"DQ10_B"
$PN"256"93;
"DQ9_B"
$PN"113"92;
"DQ8_B"
$PN"111"91;
"DQ7_B"
$PN"254"90;
"DQ6_B"
$PN"252"89;
"DQ5_B"
$PN"109"88;
"DQ4_B"
$PN"107"87;
"DQ3_B"
$PN"247"86;
"DQ2_B"
$PN"245"85;
"DQ1_B"
$PN"102"84;
"DQ0_B"
$PN"100"83;
"HAS"
$PN"148"21;
"HSCL"
$PN"4"15;
"HSDA"
$PN"5"17;
"LBD||RSP_A_N"
$PN"86"82;
"LBS||RSP_B_N"
$PN"87"81;
"PAR_A"
$PN"74"80;
"PAR_B"
$PN"227"79;
"RESET_N \B"
$PN"207"23;
"RFU6"
$PN"232"78;
"RFU5"
$PN"231"20;
"RFU4"
$PN"220"19;
"RFU3"
$PN"150"18;
"RFU2"
$PN"149"77;
"RFU1"
$PN"144"76;
"RFU0"
$PN"2"75;
"VIN_MGMT"
$PN"3"22;
%"TAP"
"1","(-3425,3375)","0","mstr_standard","I220";
;
CDS_LIB"mstr_standard"
BODY_TYPE"PLUMBING"
HDL_TAP"TRUE";
"B \NAC \NWC"10;
"S \NAC"
BN"9"31;
%"TAP"
"1","(-3425,3275)","0","mstr_standard","I221";
;
CDS_LIB"mstr_standard"
BODY_TYPE"PLUMBING"
HDL_TAP"TRUE";
"B \NAC \NWC"10;
"S \NAC"
BN"8"67;
%"TAP"
"1","(-3225,3125)","0","mstr_standard","I222";
;
CDS_LIB"mstr_standard"
BODY_TYPE"PLUMBING"
HDL_TAP"TRUE";
"B \NAC \NWC"9;
"S \NAC"
BN"7"36;
%"TAP"
"1","(-3225,3025)","0","mstr_standard","I223";
;
CDS_LIB"mstr_standard"
BODY_TYPE"PLUMBING"
HDL_TAP"TRUE";
"B \NAC \NWC"9;
"S \NAC"
BN"6"39;
%"TAP"
"1","(-3225,2925)","0","mstr_standard","I224";
;
CDS_LIB"mstr_standard"
BODY_TYPE"PLUMBING"
HDL_TAP"TRUE";
"B \NAC \NWC"9;
"S \NAC"
BN"5"42;
%"TAP"
"1","(-3225,2725)","0","mstr_standard","I225";
;
CDS_LIB"mstr_standard"
BODY_TYPE"PLUMBING"
HDL_TAP"TRUE";
"B \NAC \NWC"9;
"S \NAC"
BN"3"50;
%"TAP"
"1","(-3225,2825)","0","mstr_standard","I226";
;
CDS_LIB"mstr_standard"
BODY_TYPE"PLUMBING"
HDL_TAP"TRUE";
"B \NAC \NWC"9;
"S \NAC"
BN"4"46;
%"TAP"
"1","(-3225,2625)","0","mstr_standard","I227";
;
CDS_LIB"mstr_standard"
BODY_TYPE"PLUMBING"
HDL_TAP"TRUE";
"B \NAC \NWC"9;
"S \NAC"
BN"2"54;
%"TAP"
"1","(-3225,2525)","0","mstr_standard","I228";
;
CDS_LIB"mstr_standard"
BODY_TYPE"PLUMBING"
HDL_TAP"TRUE";
"B \NAC \NWC"9;
"S \NAC"
BN"1"58;
%"TAP"
"1","(-3225,2425)","0","mstr_standard","I229";
;
CDS_LIB"mstr_standard"
BODY_TYPE"PLUMBING"
HDL_TAP"TRUE";
"B \NAC \NWC"9;
"S \NAC"
BN"0"62;
%"TAP"
"1","(-7650,3300)","2","mstr_standard","I23";
;
CDS_LIB"mstr_standard"
BODY_TYPE"PLUMBING"
HDL_TAP"TRUE";
"B \NAC \NWC"4;
"S \NAC"
BN"2"149;
%"TAP"
"1","(-3425,3175)","0","mstr_standard","I230";
;
CDS_LIB"mstr_standard"
BODY_TYPE"PLUMBING"
HDL_TAP"TRUE";
"B \NAC \NWC"10;
"S \NAC"
BN"7"65;
%"TAP"
"1","(-3425,3075)","0","mstr_standard","I231";
;
CDS_LIB"mstr_standard"
BODY_TYPE"PLUMBING"
HDL_TAP"TRUE";
"B \NAC \NWC"10;
"S \NAC"
BN"6"38;
%"TAP"
"1","(-3425,2975)","0","mstr_standard","I232";
;
CDS_LIB"mstr_standard"
BODY_TYPE"PLUMBING"
HDL_TAP"TRUE";
"B \NAC \NWC"10;
"S \NAC"
BN"5"41;
%"TAP"
"1","(-3425,2875)","0","mstr_standard","I233";
;
CDS_LIB"mstr_standard"
BODY_TYPE"PLUMBING"
HDL_TAP"TRUE";
"B \NAC \NWC"10;
"S \NAC"
BN"4"45;
%"TAP"
"1","(-3425,2775)","0","mstr_standard","I234";
;
CDS_LIB"mstr_standard"
BODY_TYPE"PLUMBING"
HDL_TAP"TRUE";
"B \NAC \NWC"10;
"S \NAC"
BN"3"49;
%"TAP"
"1","(-3425,2675)","0","mstr_standard","I235";
;
CDS_LIB"mstr_standard"
BODY_TYPE"PLUMBING"
HDL_TAP"TRUE";
"B \NAC \NWC"10;
"S \NAC"
BN"2"53;
%"TAP"
"1","(-3425,2575)","0","mstr_standard","I236";
;
CDS_LIB"mstr_standard"
BODY_TYPE"PLUMBING"
HDL_TAP"TRUE";
"B \NAC \NWC"10;
"S \NAC"
BN"1"57;
%"TAP"
"1","(-3425,2475)","0","mstr_standard","I237";
;
CDS_LIB"mstr_standard"
BODY_TYPE"PLUMBING"
HDL_TAP"TRUE";
"B \NAC \NWC"10;
"S \NAC"
BN"0"61;
%"SCONN288_DDR506112002KQ"
"2","(-4375,3425)","0","pure_quanta","I238";
;
LOCATION"J27"
$SEC"2"
CDS_SEC"2"
PART_TYPE"SMLF"
MATERIAL"IO"
PART_NUMBER"DFHST8FS479"
VALUE"SCONN288_DDR506112002KQ"
CDS_LMAN_SYM_OUTLINE"-600,1150,600,-1150"
NEEDS_NO_SIZE"TRUE"
CDS_LIB"pure_quanta";
"DQS7_A_C||TDQS7_A_C \B"
$PN"178"69;
"DQS6_A_T||TDQS6_A_T"
$PN"168"68;
"DQS8_B_T||TDQS8_B_T"
$PN"283"67;
"DQS8_B_C||TDQS8_B_C \B"
$PN"282"66;
"DQS7_B_T||TDQS7_B_T"
$PN"272"65;
"DQS0_A_C \B"
$PN"12"64;
"DQS0_A_T"
$PN"11"63;
"DQS0_B_C \B"
$PN"105"62;
"DQS0_B_T"
$PN"104"61;
"DQS1_A_C \B"
$PN"23"60;
"DQS1_A_T"
$PN"22"59;
"DQS1_B_C \B"
$PN"116"58;
"DQS1_B_T"
$PN"115"57;
"DQS2_A_C \B"
$PN"34"56;
"DQS2_A_T"
$PN"33"55;
"DQS2_B_C \B"
$PN"127"54;
"DQS2_B_T"
$PN"126"53;
"DQS3_A_C \B"
$PN"45"52;
"DQS3_A_T"
$PN"44"51;
"DQS3_B_C \B"
$PN"138"50;
"DQS3_B_T"
$PN"137"49;
"DQS4_A_C \B"
$PN"56"48;
"DQS4_A_T"
$PN"55"47;
"DQS4_B_C \B"
$PN"238"46;
"DQS4_B_T"
$PN"239"45;
"DQS5_A_C||TDQS5_A_C||DQS5_A_T||TDQS5_A_T \B"
$PN"156"44;
"DQS5_A_T||TDQS5_A_T"
$PN"157"43;
"DQS5_B_C||TDQS5_B_C \B"
$PN"249"42;
"DQS5_B_T||TDQS5_B_T"
$PN"250"41;
"DQS6_A_C||TDQS6_A_C||DQS6_A_T||TDQS6_A_T \B"
$PN"167"40;
"DQS6_B_C||TDQS6_B_C \B"
$PN"260"39;
"DQS6_B_T||TDQS6_B_T"
$PN"261"38;
"DQS7_A_T||TDQS7_A_T"
$PN"179"37;
"DQS7_B_C||TDQS7_B_C \B"
$PN"271"36;
"DQS8_A_C||TDQS8_A_C \B"
$PN"189"35;
"DQS8_A_T||TDQS8_A_T"
$PN"190"34;
"DQS9_A_C||TDQS9_A_C \B"
$PN"200"30;
"DQS9_A_T||TDQS9_A_T"
$PN"201"33;
"DQS9_B_C||TDQS9_B_C \B"
$PN"94"32;
"DQS9_B_T||TDQS9_B_T||DBI4_B_N"
$PN"93"31;
%"GND"
"1","(-2825,5525)","0","pure_quanta_power","I239";
;
CDS_LIB"pure_quanta_power"
BOM_COST"MEM"
SIZE"1B"
ROOM"MEM_EFGH_DECOUPLING_CAPS"
HDL_POWER"GND";
"A<SIZE-1..0>\NAC"176;
%"TAP"
"1","(-7650,3350)","2","mstr_standard","I24";
;
CDS_LIB"mstr_standard"
BODY_TYPE"PLUMBING"
HDL_TAP"TRUE";
"B \NAC \NWC"4;
"S \NAC"
BN"3"150;
%"Q_CAP"
"1","(-2825,5875)","2","pure_quanta","I240";
;
LOCATION"C532"
$SEC"1"
CDS_SEC"1"
MATERIAL"X6S"
TOLERANCE"10%"
VALUE"10UF"
PART_NUMBER"CH6104KEA00"
VOLTAGE"25V"
PACK_TYPE"C0805"
BOM_COST"MEM"
CDS_LIB"pure_quanta"
ROOM"MEM_CH_A_CPU0_DIMM1";
"B"
$PN"2"176;
"A"
$PN"1"25;
%"Q_CAP"
"1","(-2250,5875)","2","pure_quanta","I241";
;
LOCATION"C533"
$SEC"1"
CDS_SEC"1"
MATERIAL"X6S"
TOLERANCE"10%"
VALUE"10UF"
VOLTAGE"25V"
PACK_TYPE"C0805"
PART_NUMBER"CH6104KEA00"
BOM_COST"MEM"
CDS_LIB"pure_quanta"
ROOM"MEM_CH_A_CPU0_DIMM1";
"B"
$PN"2"176;
"A"
$PN"1"25;
%"UNIVERSAL_POWER"
"1","(-2825,6200)","0","pure_quanta_power","I242";
;
HDL_POWER"P12V_MEM_1"
CDS_LIB"pure_quanta_power";
"A"25;
%"Q_RES"
"1","(-7700,2700)","0","pure_quanta","I244";
;
$LOCATION"R1587"
CDS_LOCATION"R1587"
$SEC"1"
CDS_SEC"1"
VALUE"49.9"
CDS_LIB"pure_quanta"
MATERIAL"CHIP"
PACK_TYPE"0402LF"
WATTAGE"1/16W"
TOLERANCE"1%"
PART_NUMBER"CS04992FB07";
"B"
$PN"2"15;
"A"
$PN"1"14;
%"TAP"
"1","(-7650,3250)","2","mstr_standard","I25";
;
CDS_LIB"mstr_standard"
BODY_TYPE"PLUMBING"
HDL_TAP"TRUE";
"B \NAC \NWC"4;
"S \NAC"
BN"1"148;
%"TAP"
"1","(-7650,3200)","2","mstr_standard","I26";
;
CDS_LIB"mstr_standard"
BODY_TYPE"PLUMBING"
HDL_TAP"TRUE";
"B \NAC \NWC"4;
"S \NAC"
BN"0"147;
%"TAP"
"1","(-7650,3400)","2","mstr_standard","I27";
;
CDS_LIB"mstr_standard"
BODY_TYPE"PLUMBING"
HDL_TAP"TRUE";
"B \NAC \NWC"4;
"S \NAC"
BN"4"151;
%"TAP"
"1","(-7650,3450)","2","mstr_standard","I28";
;
CDS_LIB"mstr_standard"
BODY_TYPE"PLUMBING"
HDL_TAP"TRUE";
"B \NAC \NWC"4;
"S \NAC"
BN"5"152;
%"TAP"
"1","(-7650,3500)","2","mstr_standard","I29";
;
CDS_LIB"mstr_standard"
BODY_TYPE"PLUMBING"
HDL_TAP"TRUE";
"B \NAC \NWC"4;
"S \NAC"
BN"6"153;
%"TAP"
"1","(-7650,3550)","2","mstr_standard","I30";
;
CDS_LIB"mstr_standard"
BODY_TYPE"PLUMBING"
HDL_TAP"TRUE";
"B \NAC \NWC"4;
"S \NAC"
BN"7"171;
%"TAP"
"1","(-7650,3650)","2","mstr_standard","I31";
;
CDS_LIB"mstr_standard"
BODY_TYPE"PLUMBING"
HDL_TAP"TRUE";
"B \NAC \NWC"1;
"S \NAC"
BN"0"154;
%"TAP"
"1","(-7650,3700)","2","mstr_standard","I32";
;
CDS_LIB"mstr_standard"
BODY_TYPE"PLUMBING"
HDL_TAP"TRUE";
"B \NAC \NWC"1;
"S \NAC"
BN"1"172;
%"TAP"
"1","(-7650,3750)","2","mstr_standard","I33";
;
CDS_LIB"mstr_standard"
BODY_TYPE"PLUMBING"
HDL_TAP"TRUE";
"B \NAC \NWC"1;
"S \NAC"
BN"2"155;
%"TAP"
"1","(-7650,3800)","2","mstr_standard","I34";
;
CDS_LIB"mstr_standard"
BODY_TYPE"PLUMBING"
HDL_TAP"TRUE";
"B \NAC \NWC"1;
"S \NAC"
BN"3"156;
%"TAP"
"1","(-7650,3850)","2","mstr_standard","I35";
;
CDS_LIB"mstr_standard"
BODY_TYPE"PLUMBING"
HDL_TAP"TRUE";
"B \NAC \NWC"1;
"S \NAC"
BN"4"173;
%"TAP"
"1","(-5950,2200)","0","mstr_standard","I36";
;
CDS_LIB"mstr_standard"
BODY_TYPE"PLUMBING"
HDL_TAP"TRUE";
"B \NAC \NWC"6;
"S \NAC"
BN"0"83;
%"TAP"
"1","(-5950,2300)","0","mstr_standard","I37";
;
CDS_LIB"mstr_standard"
BODY_TYPE"PLUMBING"
HDL_TAP"TRUE";
"B \NAC \NWC"6;
"S \NAC"
BN"2"85;
%"TAP"
"1","(-5950,2350)","0","mstr_standard","I38";
;
CDS_LIB"mstr_standard"
BODY_TYPE"PLUMBING"
HDL_TAP"TRUE";
"B \NAC \NWC"6;
"S \NAC"
BN"3"86;
%"TAP"
"1","(-5950,2250)","0","mstr_standard","I39";
;
CDS_LIB"mstr_standard"
BODY_TYPE"PLUMBING"
HDL_TAP"TRUE";
"B \NAC \NWC"6;
"S \NAC"
BN"1"84;
%"TAP"
"1","(-5950,2400)","0","mstr_standard","I40";
;
CDS_LIB"mstr_standard"
BODY_TYPE"PLUMBING"
HDL_TAP"TRUE";
"B \NAC \NWC"6;
"S \NAC"
BN"4"87;
%"TAP"
"1","(-5950,2450)","0","mstr_standard","I41";
;
CDS_LIB"mstr_standard"
BODY_TYPE"PLUMBING"
HDL_TAP"TRUE";
"B \NAC \NWC"6;
"S \NAC"
BN"5"88;
%"TAP"
"1","(-5950,2500)","0","mstr_standard","I42";
;
CDS_LIB"mstr_standard"
BODY_TYPE"PLUMBING"
HDL_TAP"TRUE";
"B \NAC \NWC"6;
"S \NAC"
BN"6"89;
%"TAP"
"1","(-5950,2550)","0","mstr_standard","I43";
;
CDS_LIB"mstr_standard"
BODY_TYPE"PLUMBING"
HDL_TAP"TRUE";
"B \NAC \NWC"6;
"S \NAC"
BN"7"90;
%"TAP"
"1","(-5950,2600)","0","mstr_standard","I44";
;
CDS_LIB"mstr_standard"
BODY_TYPE"PLUMBING"
HDL_TAP"TRUE";
"B \NAC \NWC"6;
"S \NAC"
BN"8"91;
%"TAP"
"1","(-5950,2650)","0","mstr_standard","I45";
;
CDS_LIB"mstr_standard"
BODY_TYPE"PLUMBING"
HDL_TAP"TRUE";
"B \NAC \NWC"6;
"S \NAC"
BN"9"92;
%"TAP"
"1","(-5950,2700)","0","mstr_standard","I46";
;
CDS_LIB"mstr_standard"
BODY_TYPE"PLUMBING"
HDL_TAP"TRUE";
"B \NAC \NWC"6;
"S \NAC"
BN"10"93;
%"TAP"
"1","(-5950,2750)","0","mstr_standard","I47";
;
CDS_LIB"mstr_standard"
BODY_TYPE"PLUMBING"
HDL_TAP"TRUE";
"B \NAC \NWC"6;
"S \NAC"
BN"11"94;
%"TAP"
"1","(-5950,2850)","0","mstr_standard","I48";
;
CDS_LIB"mstr_standard"
BODY_TYPE"PLUMBING"
HDL_TAP"TRUE";
"B \NAC \NWC"6;
"S \NAC"
BN"13"96;
%"TAP"
"1","(-5950,2800)","0","mstr_standard","I49";
;
CDS_LIB"mstr_standard"
BODY_TYPE"PLUMBING"
HDL_TAP"TRUE";
"B \NAC \NWC"6;
"S \NAC"
BN"12"95;
%"TAP"
"1","(-5950,2900)","0","mstr_standard","I50";
;
CDS_LIB"mstr_standard"
BODY_TYPE"PLUMBING"
HDL_TAP"TRUE";
"B \NAC \NWC"6;
"S \NAC"
BN"14"97;
%"TAP"
"1","(-5950,2950)","0","mstr_standard","I51";
;
CDS_LIB"mstr_standard"
BODY_TYPE"PLUMBING"
HDL_TAP"TRUE";
"B \NAC \NWC"6;
"S \NAC"
BN"15"98;
%"TAP"
"1","(-5950,3000)","0","mstr_standard","I52";
;
CDS_LIB"mstr_standard"
BODY_TYPE"PLUMBING"
HDL_TAP"TRUE";
"B \NAC \NWC"6;
"S \NAC"
BN"16"99;
%"TAP"
"1","(-5950,3050)","0","mstr_standard","I53";
;
CDS_LIB"mstr_standard"
BODY_TYPE"PLUMBING"
HDL_TAP"TRUE";
"B \NAC \NWC"6;
"S \NAC"
BN"17"100;
%"TAP"
"1","(-5950,3100)","0","mstr_standard","I54";
;
CDS_LIB"mstr_standard"
BODY_TYPE"PLUMBING"
HDL_TAP"TRUE";
"B \NAC \NWC"6;
"S \NAC"
BN"18"101;
%"TAP"
"1","(-5950,3150)","0","mstr_standard","I55";
;
CDS_LIB"mstr_standard"
BODY_TYPE"PLUMBING"
HDL_TAP"TRUE";
"B \NAC \NWC"6;
"S \NAC"
BN"19"102;
%"TAP"
"1","(-5950,3200)","0","mstr_standard","I56";
;
CDS_LIB"mstr_standard"
BODY_TYPE"PLUMBING"
HDL_TAP"TRUE";
"B \NAC \NWC"6;
"S \NAC"
BN"20"103;
%"TAP"
"1","(-5950,3250)","0","mstr_standard","I57";
;
CDS_LIB"mstr_standard"
BODY_TYPE"PLUMBING"
HDL_TAP"TRUE";
"B \NAC \NWC"6;
"S \NAC"
BN"21"104;
%"TAP"
"1","(-5950,3300)","0","mstr_standard","I58";
;
CDS_LIB"mstr_standard"
BODY_TYPE"PLUMBING"
HDL_TAP"TRUE";
"B \NAC \NWC"6;
"S \NAC"
BN"22"105;
%"TAP"
"1","(-5950,3350)","0","mstr_standard","I59";
;
CDS_LIB"mstr_standard"
BODY_TYPE"PLUMBING"
HDL_TAP"TRUE";
"B \NAC \NWC"6;
"S \NAC"
BN"23"106;
%"TAP"
"1","(-5950,3400)","0","mstr_standard","I60";
;
CDS_LIB"mstr_standard"
BODY_TYPE"PLUMBING"
HDL_TAP"TRUE";
"B \NAC \NWC"6;
"S \NAC"
BN"24"107;
%"TAP"
"1","(-5950,3450)","0","mstr_standard","I61";
;
CDS_LIB"mstr_standard"
BODY_TYPE"PLUMBING"
HDL_TAP"TRUE";
"B \NAC \NWC"6;
"S \NAC"
BN"25"108;
%"TAP"
"1","(-5950,3500)","0","mstr_standard","I62";
;
CDS_LIB"mstr_standard"
BODY_TYPE"PLUMBING"
HDL_TAP"TRUE";
"B \NAC \NWC"6;
"S \NAC"
BN"26"109;
%"TAP"
"1","(-5950,3550)","0","mstr_standard","I63";
;
CDS_LIB"mstr_standard"
BODY_TYPE"PLUMBING"
HDL_TAP"TRUE";
"B \NAC \NWC"6;
"S \NAC"
BN"27"110;
%"TAP"
"1","(-5950,3600)","0","mstr_standard","I64";
;
CDS_LIB"mstr_standard"
BODY_TYPE"PLUMBING"
HDL_TAP"TRUE";
"B \NAC \NWC"6;
"S \NAC"
BN"28"111;
%"TAP"
"1","(-5950,3650)","0","mstr_standard","I65";
;
CDS_LIB"mstr_standard"
BODY_TYPE"PLUMBING"
HDL_TAP"TRUE";
"B \NAC \NWC"6;
"S \NAC"
BN"29"112;
%"TAP"
"1","(-5950,3750)","0","mstr_standard","I66";
;
CDS_LIB"mstr_standard"
BODY_TYPE"PLUMBING"
HDL_TAP"TRUE";
"B \NAC \NWC"6;
"S \NAC"
BN"31"114;
%"TAP"
"1","(-5950,3700)","0","mstr_standard","I67";
;
CDS_LIB"mstr_standard"
BODY_TYPE"PLUMBING"
HDL_TAP"TRUE";
"B \NAC \NWC"6;
"S \NAC"
BN"30"113;
%"TAP"
"1","(-5950,3850)","0","mstr_standard","I68";
;
CDS_LIB"mstr_standard"
BODY_TYPE"PLUMBING"
HDL_TAP"TRUE";
"B \NAC \NWC"5;
"S \NAC"
BN"0"115;
%"TAP"
"1","(-7650,4000)","2","mstr_standard","I77";
;
CDS_LIB"mstr_standard"
BODY_TYPE"PLUMBING"
HDL_TAP"TRUE";
"B \NAC \NWC"1;
"S \NAC"
BN"7"174;
%"TAP"
"1","(-7650,3950)","2","mstr_standard","I78";
;
CDS_LIB"mstr_standard"
BODY_TYPE"PLUMBING"
HDL_TAP"TRUE";
"B \NAC \NWC"1;
"S \NAC"
BN"6"158;
%"TAP"
"1","(-7650,3900)","2","mstr_standard","I79";
;
CDS_LIB"mstr_standard"
BODY_TYPE"PLUMBING"
HDL_TAP"TRUE";
"B \NAC \NWC"1;
"S \NAC"
BN"5"157;
%"TAP"
"1","(-7650,4850)","2","mstr_standard","I80";
;
CDS_LIB"mstr_standard"
BODY_TYPE"PLUMBING"
HDL_TAP"TRUE";
"B \NAC \NWC"3;
"S \NAC"
BN"3"163;
%"TAP"
"1","(-7650,4800)","2","mstr_standard","I81";
;
CDS_LIB"mstr_standard"
BODY_TYPE"PLUMBING"
HDL_TAP"TRUE";
"B \NAC \NWC"3;
"S \NAC"
BN"2"165;
%"TAP"
"1","(-7650,4750)","2","mstr_standard","I82";
;
CDS_LIB"mstr_standard"
BODY_TYPE"PLUMBING"
HDL_TAP"TRUE";
"B \NAC \NWC"3;
"S \NAC"
BN"1"167;
%"TAP"
"1","(-7650,4700)","2","mstr_standard","I83";
;
CDS_LIB"mstr_standard"
BODY_TYPE"PLUMBING"
HDL_TAP"TRUE";
"B \NAC \NWC"3;
"S \NAC"
BN"0"169;
%"TAP"
"1","(-7650,4900)","2","mstr_standard","I84";
;
CDS_LIB"mstr_standard"
BODY_TYPE"PLUMBING"
HDL_TAP"TRUE";
"B \NAC \NWC"3;
"S \NAC"
BN"4"162;
%"TAP"
"1","(-7650,4950)","2","mstr_standard","I85";
;
CDS_LIB"mstr_standard"
BODY_TYPE"PLUMBING"
HDL_TAP"TRUE";
"B \NAC \NWC"3;
"S \NAC"
BN"5"161;
%"TAP"
"1","(-7650,5000)","2","mstr_standard","I86";
;
CDS_LIB"mstr_standard"
BODY_TYPE"PLUMBING"
HDL_TAP"TRUE";
"B \NAC \NWC"3;
"S \NAC"
BN"6"159;
%"TAP"
"1","(-7650,5150)","2","mstr_standard","I87";
;
CDS_LIB"mstr_standard"
BODY_TYPE"PLUMBING"
HDL_TAP"TRUE";
"B \NAC \NWC"2;
"S \NAC"
BN"1"168;
%"TAP"
"1","(-7650,5100)","2","mstr_standard","I88";
;
CDS_LIB"mstr_standard"
BODY_TYPE"PLUMBING"
HDL_TAP"TRUE";
"B \NAC \NWC"2;
"S \NAC"
BN"0"170;
%"TAP"
"1","(-7650,5200)","2","mstr_standard","I89";
;
CDS_LIB"mstr_standard"
BODY_TYPE"PLUMBING"
HDL_TAP"TRUE";
"B \NAC \NWC"2;
"S \NAC"
BN"2"166;
%"VCC_CORE"
"1","(-8475,3425)","0","mstr_symbols","I9";
;
HDL_POWER"P3V3_STBY"
CDS_LIB"mstr_symbols"
VOLTAGE"3.3"
ROOM"PVCCINFAON_CPU1_CTRL";
"A"22;
%"TAP"
"1","(-7650,5250)","2","mstr_standard","I90";
;
CDS_LIB"mstr_standard"
BODY_TYPE"PLUMBING"
HDL_TAP"TRUE";
"B \NAC \NWC"2;
"S \NAC"
BN"3"164;
%"TAP"
"1","(-7650,5300)","2","mstr_standard","I91";
;
CDS_LIB"mstr_standard"
BODY_TYPE"PLUMBING"
HDL_TAP"TRUE";
"B \NAC \NWC"2;
"S \NAC"
BN"4"71;
%"TAP"
"1","(-7650,5400)","2","mstr_standard","I92";
;
CDS_LIB"mstr_standard"
BODY_TYPE"PLUMBING"
HDL_TAP"TRUE";
"B \NAC \NWC"2;
"S \NAC"
BN"6"160;
%"TAP"
"1","(-7650,5350)","2","mstr_standard","I93";
;
CDS_LIB"mstr_standard"
BODY_TYPE"PLUMBING"
HDL_TAP"TRUE";
"B \NAC \NWC"2;
"S \NAC"
BN"5"70;
%"TAP"
"1","(-5950,3900)","0","mstr_standard","I94";
;
CDS_LIB"mstr_standard"
BODY_TYPE"PLUMBING"
HDL_TAP"TRUE";
"B \NAC \NWC"5;
"S \NAC"
BN"1"116;
%"TAP"
"1","(-5950,3950)","0","mstr_standard","I95";
;
CDS_LIB"mstr_standard"
BODY_TYPE"PLUMBING"
HDL_TAP"TRUE";
"B \NAC \NWC"5;
"S \NAC"
BN"2"117;
%"TAP"
"1","(-5950,4000)","0","mstr_standard","I96";
;
CDS_LIB"mstr_standard"
BODY_TYPE"PLUMBING"
HDL_TAP"TRUE";
"B \NAC \NWC"5;
"S \NAC"
BN"3"118;
%"TAP"
"1","(-5950,4150)","0","mstr_standard","I97";
;
CDS_LIB"mstr_standard"
BODY_TYPE"PLUMBING"
HDL_TAP"TRUE";
"B \NAC \NWC"5;
"S \NAC"
BN"6"121;
%"TAP"
"1","(-5950,4050)","0","mstr_standard","I98";
;
CDS_LIB"mstr_standard"
BODY_TYPE"PLUMBING"
HDL_TAP"TRUE";
"B \NAC \NWC"5;
"S \NAC"
BN"4"119;
%"TAP"
"1","(-5950,4100)","0","mstr_standard","I99";
;
CDS_LIB"mstr_standard"
BODY_TYPE"PLUMBING"
HDL_TAP"TRUE";
"B \NAC \NWC"5;
"S \NAC"
BN"5"120;
END.
